(kicad_pcb
	(version 20260206)
	(generator "pcbnew")
	(generator_version "10.0")
	(general
		(thickness 1.6)
		(legacy_teardrops no)
	)
	(paper "A4")
	(title_block
		(title "01162023_DA0F0TEBIF0_F0T_Expander_BD_F_brd_V02_OCP.brd")
		(comment 1 "Grand Teton / footprints 6033-6039 of 9728")
	)
	(layers
		(0 "F.Cu" signal "TOP")
		(4 "In1.Cu" signal "GND")
		(6 "In2.Cu" signal "VCC")
		(8 "In3.Cu" signal "VCC1")
		(10 "In4.Cu" signal "GND1")
		(12 "In5.Cu" signal "IN1")
		(14 "In6.Cu" signal "GND2")
		(16 "In7.Cu" signal "IN2")
		(18 "In8.Cu" signal "GND3")
		(20 "In9.Cu" signal "IN3")
		(22 "In10.Cu" signal "GND4")
		(24 "In11.Cu" signal "IN4")
		(26 "In12.Cu" signal "GND5")
		(28 "In13.Cu" signal "IN5")
		(30 "In14.Cu" signal "GND6")
		(32 "In15.Cu" signal "IN6")
		(34 "In16.Cu" signal "GND7")
		(2 "B.Cu" signal "BOTTOM")
		(9 "F.Adhes" user "F.Adhesive")
		(11 "B.Adhes" user "B.Adhesive")
		(13 "F.Paste" user "Package Geometry/Pastemask Top")
		(15 "B.Paste" user "Package Geometry/Pastemask Bottom")
		(5 "F.SilkS" user "Ref Des/Silkscreen Top")
		(7 "B.SilkS" user "Ref Des/Silkscreen Bottom")
		(1 "F.Mask" user "Board Geometry/Soldermask Top")
		(3 "B.Mask" user "Board Geometry/Soldermask Bottom")
		(17 "Dwgs.User" user "User.Drawings")
		(19 "Cmts.User" user "User.Comments")
		(21 "Eco1.User" user "User.Eco1")
		(23 "Eco2.User" user "User.Eco2")
		(25 "Edge.Cuts" user "Board Geometry/Outline")
		(27 "Margin" user)
		(31 "F.CrtYd" user "Package Geometry/Place Bound Top")
		(29 "B.CrtYd" user "Package Geometry/Place Bound Bottom")
		(35 "F.Fab" user "Ref Des/Assembly Top")
		(33 "B.Fab" user "Ref Des/Assembly Bottom")
	)
	(footprint ""
		(layer "F.Cu")
		(at 27.838654 -311.156604 -90)
		(property "Reference" "R1093"
			(at 0 0 270)
			(layer "F.SilkS")
			(hide yes)
			(effects
				(font
					(size 1.27 1.27)
				)
			)
		)
		(property "Value" ""
			(at 0 0 270)
			(layer "F.Fab")
			(effects
				(font
					(size 1.27 1.27)
				)
			)
		)
		(duplicate_pad_numbers_are_jumpers no)
		(fp_line
			(start -0.7874 0.4064)
			(end -0.7874 -0.4064)
			(stroke
				(width 0.1524)
				(type default)
			)
			(layer "F.SilkS")
		)
		(fp_line
			(start 0.7874 0.4064)
			(end -0.7874 0.4064)
			(stroke
				(width 0.1524)
				(type default)
			)
			(layer "F.SilkS")
		)
		(fp_line
			(start -0.7874 -0.4064)
			(end 0.7874 -0.4064)
			(stroke
				(width 0.1524)
				(type default)
			)
			(layer "F.SilkS")
		)
		(fp_line
			(start 0.7874 -0.4064)
			(end 0.7874 0.4064)
			(stroke
				(width 0.1524)
				(type default)
			)
			(layer "F.SilkS")
		)
		(fp_line
			(start -0.67945 0.3048)
			(end -0.67945 -0.305054)
			(stroke
				(width 0.1)
				(type default)
			)
			(layer "F.Fab")
		)
		(fp_line
			(start -0.12065 0.3048)
			(end -0.67945 0.3048)
			(stroke
				(width 0.1)
				(type default)
			)
			(layer "F.Fab")
		)
		(fp_line
			(start 0.120396 0.3048)
			(end 0.120396 0.2794)
			(stroke
				(width 0.1)
				(type default)
			)
			(layer "F.Fab")
		)
		(fp_line
			(start 0.67945 0.3048)
			(end 0.120396 0.3048)
			(stroke
				(width 0.1)
				(type default)
			)
			(layer "F.Fab")
		)
		(fp_line
			(start -0.12065 0.2794)
			(end -0.12065 0.3048)
			(stroke
				(width 0.1)
				(type default)
			)
			(layer "F.Fab")
		)
		(fp_line
			(start 0.120396 0.2794)
			(end -0.12065 0.2794)
			(stroke
				(width 0.1)
				(type default)
			)
			(layer "F.Fab")
		)
		(fp_line
			(start -0.12065 -0.2794)
			(end 0.12065 -0.2794)
			(stroke
				(width 0.1)
				(type default)
			)
			(layer "F.Fab")
		)
		(fp_line
			(start 0.12065 -0.2794)
			(end 0.12065 -0.3048)
			(stroke
				(width 0.1)
				(type default)
			)
			(layer "F.Fab")
		)
		(fp_line
			(start 0.12065 -0.3048)
			(end 0.67945 -0.3048)
			(stroke
				(width 0.1)
				(type default)
			)
			(layer "F.Fab")
		)
		(fp_line
			(start 0.67945 -0.3048)
			(end 0.67945 0.3048)
			(stroke
				(width 0.1)
				(type default)
			)
			(layer "F.Fab")
		)
		(fp_line
			(start -0.67945 -0.305054)
			(end -0.12065 -0.305054)
			(stroke
				(width 0.1)
				(type default)
			)
			(layer "F.Fab")
		)
		(fp_line
			(start -0.12065 -0.305054)
			(end -0.12065 -0.2794)
			(stroke
				(width 0.1)
				(type default)
			)
			(layer "F.Fab")
		)
		(pad "1" smd circle
			(at -0.40005 0 270)
			(size 0 0)
			(layers "F.Cu" "F.Mask" "F.Paste")
			(net "PEX0_DBG_SEL1")
		)
		(pad "2" smd circle
			(at 0.40005 0 270)
			(size 0 0)
			(layers "F.Cu" "F.Mask" "F.Paste")
			(net "P1V8_PEX")
		)
	)
	(footprint ""
		(layer "F.Cu")
		(at 358.013 -211.328 180)
		(property "Reference" "R4096"
			(at 0 0 180)
			(layer "F.SilkS")
			(hide yes)
			(effects
				(font
					(size 1.27 1.27)
				)
			)
		)
		(property "Value" ""
			(at 0 0 180)
			(layer "F.Fab")
			(effects
				(font
					(size 1.27 1.27)
				)
			)
		)
		(duplicate_pad_numbers_are_jumpers no)
		(fp_line
			(start 0.7874 0.4064)
			(end -0.7874 0.4064)
			(stroke
				(width 0.1524)
				(type default)
			)
			(layer "F.SilkS")
		)
		(fp_line
			(start 0.7874 -0.4064)
			(end 0.7874 0.4064)
			(stroke
				(width 0.1524)
				(type default)
			)
			(layer "F.SilkS")
		)
		(fp_line
			(start -0.7874 0.4064)
			(end -0.7874 -0.4064)
			(stroke
				(width 0.1524)
				(type default)
			)
			(layer "F.SilkS")
		)
		(fp_line
			(start -0.7874 -0.4064)
			(end 0.7874 -0.4064)
			(stroke
				(width 0.1524)
				(type default)
			)
			(layer "F.SilkS")
		)
		(fp_line
			(start 0.67945 0.3048)
			(end 0.120396 0.3048)
			(stroke
				(width 0.1)
				(type default)
			)
			(layer "F.Fab")
		)
		(fp_line
			(start 0.67945 -0.3048)
			(end 0.67945 0.3048)
			(stroke
				(width 0.1)
				(type default)
			)
			(layer "F.Fab")
		)
		(fp_line
			(start 0.12065 -0.2794)
			(end 0.12065 -0.3048)
			(stroke
				(width 0.1)
				(type default)
			)
			(layer "F.Fab")
		)
		(fp_line
			(start 0.12065 -0.3048)
			(end 0.67945 -0.3048)
			(stroke
				(width 0.1)
				(type default)
			)
			(layer "F.Fab")
		)
		(fp_line
			(start 0.120396 0.3048)
			(end 0.120396 0.2794)
			(stroke
				(width 0.1)
				(type default)
			)
			(layer "F.Fab")
		)
		(fp_line
			(start 0.120396 0.2794)
			(end -0.12065 0.2794)
			(stroke
				(width 0.1)
				(type default)
			)
			(layer "F.Fab")
		)
		(fp_line
			(start -0.12065 0.3048)
			(end -0.67945 0.3048)
			(stroke
				(width 0.1)
				(type default)
			)
			(layer "F.Fab")
		)
		(fp_line
			(start -0.12065 0.2794)
			(end -0.12065 0.3048)
			(stroke
				(width 0.1)
				(type default)
			)
			(layer "F.Fab")
		)
		(fp_line
			(start -0.12065 -0.2794)
			(end 0.12065 -0.2794)
			(stroke
				(width 0.1)
				(type default)
			)
			(layer "F.Fab")
		)
		(fp_line
			(start -0.12065 -0.305054)
			(end -0.12065 -0.2794)
			(stroke
				(width 0.1)
				(type default)
			)
			(layer "F.Fab")
		)
		(fp_line
			(start -0.67945 0.3048)
			(end -0.67945 -0.305054)
			(stroke
				(width 0.1)
				(type default)
			)
			(layer "F.Fab")
		)
		(fp_line
			(start -0.67945 -0.305054)
			(end -0.12065 -0.305054)
			(stroke
				(width 0.1)
				(type default)
			)
			(layer "F.Fab")
		)
		(pad "1" smd circle
			(at -0.40005 0 180)
			(size 0 0)
			(layers "F.Cu" "F.Mask" "F.Paste")
			(net "PRSNT_NIC4_FPGA_R_N")
		)
		(pad "2" smd circle
			(at 0.40005 0 180)
			(size 0 0)
			(layers "F.Cu" "F.Mask" "F.Paste")
			(net "PRSNT_NIC4_FPGA_N")
		)
	)
	(footprint ""
		(layer "F.Cu")
		(at 82.661506 -147.99691 180)
		(property "Reference" "C10"
			(at 0 0 180)
			(layer "F.SilkS")
			(hide yes)
			(effects
				(font
					(size 1.27 1.27)
				)
			)
		)
		(property "Value" ""
			(at 0 0 180)
			(layer "F.Fab")
			(effects
				(font
					(size 1.27 1.27)
				)
			)
		)
		(duplicate_pad_numbers_are_jumpers no)
		(fp_line
			(start 0.299974 0.150114)
			(end -0.299974 0.150114)
			(stroke
				(width 0.1)
				(type default)
			)
			(layer "F.Fab")
		)
		(fp_line
			(start 0.299974 -0.150114)
			(end 0.299974 0.150114)
			(stroke
				(width 0.1)
				(type default)
			)
			(layer "F.Fab")
		)
		(fp_line
			(start -0.299974 0.150114)
			(end -0.299974 -0.150114)
			(stroke
				(width 0.1)
				(type default)
			)
			(layer "F.Fab")
		)
		(fp_line
			(start -0.299974 -0.150114)
			(end 0.299974 -0.150114)
			(stroke
				(width 0.1)
				(type default)
			)
			(layer "F.Fab")
		)
		(pad "1" smd rect
			(at -0.2667 0 180)
			(size 0.3048 0.381)
			(layers "F.Cu" "F.Mask" "F.Paste")
			(net "P5E_PEX0_STN0_TX_DN<11>")
		)
		(pad "2" smd rect
			(at 0.2667 0 180)
			(size 0.3048 0.381)
			(layers "F.Cu" "F.Mask" "F.Paste")
			(net "P5E_PEX0_STN0_TX_C_DN<11>")
		)
	)
	(footprint ""
		(layer "F.Cu")
		(at 365.980726 -258.758182 90)
		(property "Reference" "U379"
			(at -1.8034 -1.819148 90)
			(unlocked yes)
			(layer "F.SilkS")
			(effects
				(font
					(size 0.7874 0.5842)
					(thickness 0.1524)
				)
				(justify left)
			)
		)
		(property "Value" ""
			(at 0 0 90)
			(layer "F.Fab")
			(effects
				(font
					(size 1.27 1.27)
				)
			)
		)
		(duplicate_pad_numbers_are_jumpers no)
		(fp_line
			(start 1.684274 -1.074928)
			(end 1.684274 1.074928)
			(stroke
				(width 0.1524)
				(type default)
			)
			(layer "F.SilkS")
		)
		(fp_line
			(start 0.381 -1.074928)
			(end 1.684274 -1.074928)
			(stroke
				(width 0.1524)
				(type default)
			)
			(layer "F.SilkS")
		)
		(fp_line
			(start -0.381 -1.074928)
			(end 0 -0.625094)
			(stroke
				(width 0.1524)
				(type default)
			)
			(layer "F.SilkS")
		)
		(fp_line
			(start -1.684274 -1.074928)
			(end -0.381 -1.074928)
			(stroke
				(width 0.1524)
				(type default)
			)
			(layer "F.SilkS")
		)
		(fp_line
			(start 0 -0.625094)
			(end 0.381 -1.074928)
			(stroke
				(width 0.1524)
				(type default)
			)
			(layer "F.SilkS")
		)
		(fp_line
			(start 1.684274 1.074928)
			(end -1.684274 1.074928)
			(stroke
				(width 0.1524)
				(type default)
			)
			(layer "F.SilkS")
		)
		(fp_line
			(start -1.684274 1.074928)
			(end -1.684274 -1.074928)
			(stroke
				(width 0.1524)
				(type default)
			)
			(layer "F.SilkS")
		)
		(fp_poly
			(pts
				(xy -2.637282 -0.903986) (xy -2.637282 -0.395986) (xy -1.875282 -0.649986)
			)
			(stroke
				(width 0)
				(type default)
			)
			(fill yes)
			(layer "F.SilkS")
		)
		(fp_line
			(start 0.700024 -1.074928)
			(end -0.700024 -1.074928)
			(stroke
				(width 0.1)
				(type default)
			)
			(layer "F.Fab")
		)
		(fp_line
			(start -0.700024 -1.074928)
			(end -0.700024 1.074928)
			(stroke
				(width 0.1)
				(type default)
			)
			(layer "F.Fab")
		)
		(fp_line
			(start 0.700024 1.074928)
			(end 0.700024 -1.074928)
			(stroke
				(width 0.1)
				(type default)
			)
			(layer "F.Fab")
		)
		(fp_line
			(start -0.700024 1.074928)
			(end 0.700024 1.074928)
			(stroke
				(width 0.1)
				(type default)
			)
			(layer "F.Fab")
		)
		(fp_poly
			(pts
				(xy -2.637282 -0.903986) (xy -2.637282 -0.395986) (xy -1.875282 -0.649986)
			)
			(stroke
				(width 0)
				(type default)
			)
			(fill yes)
			(layer "F.Fab")
		)
		(pad "1" smd rect
			(at -1.100074 -0.649986)
			(size 0.4064 0.9144)
			(layers "F.Cu" "F.Mask" "F.Paste")
			(net "Net_9085")
		)
		(pad "2" smd rect
			(at -1.100074 0)
			(size 0.4064 0.9144)
			(layers "F.Cu" "F.Mask" "F.Paste")
			(net "PWR_EN_PEX_R1")
		)
		(pad "3" smd rect
			(at -1.100074 0.649986)
			(size 0.4064 0.9144)
			(layers "F.Cu" "F.Mask" "F.Paste")
			(net "GND")
		)
		(pad "4" smd rect
			(at 1.100074 0.649986)
			(size 0.4064 0.9144)
			(layers "F.Cu" "F.Mask" "F.Paste")
			(net "PWR_EN_PEX_BUF")
		)
		(pad "5" smd rect
			(at 1.100074 -0.649986)
			(size 0.4064 0.9144)
			(layers "F.Cu" "F.Mask" "F.Paste")
			(net "P3V3_AUX")
		)
	)
	(footprint ""
		(layer "F.Cu")
		(at 359.156 -186.182 180)
		(property "Reference" "R4614"
			(at 0 0 180)
			(layer "F.SilkS")
			(hide yes)
			(effects
				(font
					(size 1.27 1.27)
				)
			)
		)
		(property "Value" ""
			(at 0 0 180)
			(layer "F.Fab")
			(effects
				(font
					(size 1.27 1.27)
				)
			)
		)
		(duplicate_pad_numbers_are_jumpers no)
		(fp_line
			(start 0.7874 0.4064)
			(end -0.7874 0.4064)
			(stroke
				(width 0.1524)
				(type default)
			)
			(layer "F.SilkS")
		)
		(fp_line
			(start 0.7874 -0.4064)
			(end 0.7874 0.4064)
			(stroke
				(width 0.1524)
				(type default)
			)
			(layer "F.SilkS")
		)
		(fp_line
			(start -0.7874 0.4064)
			(end -0.7874 -0.4064)
			(stroke
				(width 0.1524)
				(type default)
			)
			(layer "F.SilkS")
		)
		(fp_line
			(start -0.7874 -0.4064)
			(end 0.7874 -0.4064)
			(stroke
				(width 0.1524)
				(type default)
			)
			(layer "F.SilkS")
		)
		(fp_line
			(start 0.67945 0.3048)
			(end 0.120396 0.3048)
			(stroke
				(width 0.1)
				(type default)
			)
			(layer "F.Fab")
		)
		(fp_line
			(start 0.67945 -0.3048)
			(end 0.67945 0.3048)
			(stroke
				(width 0.1)
				(type default)
			)
			(layer "F.Fab")
		)
		(fp_line
			(start 0.12065 -0.2794)
			(end 0.12065 -0.3048)
			(stroke
				(width 0.1)
				(type default)
			)
			(layer "F.Fab")
		)
		(fp_line
			(start 0.12065 -0.3048)
			(end 0.67945 -0.3048)
			(stroke
				(width 0.1)
				(type default)
			)
			(layer "F.Fab")
		)
		(fp_line
			(start 0.120396 0.3048)
			(end 0.120396 0.2794)
			(stroke
				(width 0.1)
				(type default)
			)
			(layer "F.Fab")
		)
		(fp_line
			(start 0.120396 0.2794)
			(end -0.12065 0.2794)
			(stroke
				(width 0.1)
				(type default)
			)
			(layer "F.Fab")
		)
		(fp_line
			(start -0.12065 0.3048)
			(end -0.67945 0.3048)
			(stroke
				(width 0.1)
				(type default)
			)
			(layer "F.Fab")
		)
		(fp_line
			(start -0.12065 0.2794)
			(end -0.12065 0.3048)
			(stroke
				(width 0.1)
				(type default)
			)
			(layer "F.Fab")
		)
		(fp_line
			(start -0.12065 -0.2794)
			(end 0.12065 -0.2794)
			(stroke
				(width 0.1)
				(type default)
			)
			(layer "F.Fab")
		)
		(fp_line
			(start -0.12065 -0.305054)
			(end -0.12065 -0.2794)
			(stroke
				(width 0.1)
				(type default)
			)
			(layer "F.Fab")
		)
		(fp_line
			(start -0.67945 0.3048)
			(end -0.67945 -0.305054)
			(stroke
				(width 0.1)
				(type default)
			)
			(layer "F.Fab")
		)
		(fp_line
			(start -0.67945 -0.305054)
			(end -0.12065 -0.305054)
			(stroke
				(width 0.1)
				(type default)
			)
			(layer "F.Fab")
		)
		(pad "1" smd circle
			(at -0.40005 0 180)
			(size 0 0)
			(layers "F.Cu" "F.Mask" "F.Paste")
			(net "SSD3_PEX_PWR_EN_R")
		)
		(pad "2" smd circle
			(at 0.40005 0 180)
			(size 0 0)
			(layers "F.Cu" "F.Mask" "F.Paste")
			(net "GND")
		)
	)
	(footprint ""
		(layer "F.Cu")
		(at 329.85456 -22.867366 90)
		(property "Reference" "C3951"
			(at 0 0 90)
			(layer "F.SilkS")
			(hide yes)
			(effects
				(font
					(size 1.27 1.27)
				)
			)
		)
		(property "Value" ""
			(at 0 0 90)
			(layer "F.Fab")
			(effects
				(font
					(size 1.27 1.27)
				)
			)
		)
		(duplicate_pad_numbers_are_jumpers no)
		(fp_line
			(start 0.7874 -0.4064)
			(end 0.7874 0.4064)
			(stroke
				(width 0.1524)
				(type default)
			)
			(layer "F.SilkS")
		)
		(fp_line
			(start -0.7874 -0.4064)
			(end 0.7874 -0.4064)
			(stroke
				(width 0.1524)
				(type default)
			)
			(layer "F.SilkS")
		)
		(fp_line
			(start 0.7874 0.4064)
			(end -0.7874 0.4064)
			(stroke
				(width 0.1524)
				(type default)
			)
			(layer "F.SilkS")
		)
		(fp_line
			(start -0.7874 0.4064)
			(end -0.7874 -0.4064)
			(stroke
				(width 0.1524)
				(type default)
			)
			(layer "F.SilkS")
		)
		(fp_line
			(start -0.12065 -0.305054)
			(end -0.12065 -0.2794)
			(stroke
				(width 0.1)
				(type default)
			)
			(layer "F.Fab")
		)
		(fp_line
			(start -0.67945 -0.305054)
			(end -0.12065 -0.305054)
			(stroke
				(width 0.1)
				(type default)
			)
			(layer "F.Fab")
		)
		(fp_line
			(start 0.67945 -0.3048)
			(end 0.67945 0.3048)
			(stroke
				(width 0.1)
				(type default)
			)
			(layer "F.Fab")
		)
		(fp_line
			(start 0.12065 -0.3048)
			(end 0.67945 -0.3048)
			(stroke
				(width 0.1)
				(type default)
			)
			(layer "F.Fab")
		)
		(fp_line
			(start 0.12065 -0.2794)
			(end 0.12065 -0.3048)
			(stroke
				(width 0.1)
				(type default)
			)
			(layer "F.Fab")
		)
		(fp_line
			(start -0.12065 -0.2794)
			(end 0.12065 -0.2794)
			(stroke
				(width 0.1)
				(type default)
			)
			(layer "F.Fab")
		)
		(fp_line
			(start 0.120396 0.2794)
			(end -0.12065 0.2794)
			(stroke
				(width 0.1)
				(type default)
			)
			(layer "F.Fab")
		)
		(fp_line
			(start -0.12065 0.2794)
			(end -0.12065 0.3048)
			(stroke
				(width 0.1)
				(type default)
			)
			(layer "F.Fab")
		)
		(fp_line
			(start 0.67945 0.3048)
			(end 0.120396 0.3048)
			(stroke
				(width 0.1)
				(type default)
			)
			(layer "F.Fab")
		)
		(fp_line
			(start 0.120396 0.3048)
			(end 0.120396 0.2794)
			(stroke
				(width 0.1)
				(type default)
			)
			(layer "F.Fab")
		)
		(fp_line
			(start -0.12065 0.3048)
			(end -0.67945 0.3048)
			(stroke
				(width 0.1)
				(type default)
			)
			(layer "F.Fab")
		)
		(fp_line
			(start -0.67945 0.3048)
			(end -0.67945 -0.305054)
			(stroke
				(width 0.1)
				(type default)
			)
			(layer "F.Fab")
		)
		(pad "1" smd circle
			(at -0.40005 0 90)
			(size 0 0)
			(layers "F.Cu" "F.Mask" "F.Paste")
			(net "P12V_SSD11")
		)
		(pad "2" smd circle
			(at 0.40005 0 90)
			(size 0 0)
			(layers "F.Cu" "F.Mask" "F.Paste")
			(net "GND")
		)
	)
	(footprint ""
		(layer "F.Cu")
		(at 2.51714 -72.165972)
		(property "Reference" "R5653"
			(at 0 0 0)
			(layer "F.SilkS")
			(hide yes)
			(effects
				(font
					(size 1.27 1.27)
				)
			)
		)
		(property "Value" ""
			(at 0 0 0)
			(layer "F.Fab")
			(effects
				(font
					(size 1.27 1.27)
				)
			)
		)
		(duplicate_pad_numbers_are_jumpers no)
		(fp_line
			(start -0.7874 -0.4064)
			(end 0.7874 -0.4064)
			(stroke
				(width 0.1524)
				(type default)
			)
			(layer "F.SilkS")
		)
		(fp_line
			(start -0.7874 0.4064)
			(end -0.7874 -0.4064)
			(stroke
				(width 0.1524)
				(type default)
			)
			(layer "F.SilkS")
		)
		(fp_line
			(start 0.7874 -0.4064)
			(end 0.7874 0.4064)
			(stroke
				(width 0.1524)
				(type default)
			)
			(layer "F.SilkS")
		)
		(fp_line
			(start 0.7874 0.4064)
			(end -0.7874 0.4064)
			(stroke
				(width 0.1524)
				(type default)
			)
			(layer "F.SilkS")
		)
		(fp_line
			(start -0.67945 -0.305054)
			(end -0.12065 -0.305054)
			(stroke
				(width 0.1)
				(type default)
			)
			(layer "F.Fab")
		)
		(fp_line
			(start -0.67945 0.3048)
			(end -0.67945 -0.305054)
			(stroke
				(width 0.1)
				(type default)
			)
			(layer "F.Fab")
		)
		(fp_line
			(start -0.12065 -0.305054)
			(end -0.12065 -0.2794)
			(stroke
				(width 0.1)
				(type default)
			)
			(layer "F.Fab")
		)
		(fp_line
			(start -0.12065 -0.2794)
			(end 0.12065 -0.2794)
			(stroke
				(width 0.1)
				(type default)
			)
			(layer "F.Fab")
		)
		(fp_line
			(start -0.12065 0.2794)
			(end -0.12065 0.3048)
			(stroke
				(width 0.1)
				(type default)
			)
			(layer "F.Fab")
		)
		(fp_line
			(start -0.12065 0.3048)
			(end -0.67945 0.3048)
			(stroke
				(width 0.1)
				(type default)
			)
			(layer "F.Fab")
		)
		(fp_line
			(start 0.120396 0.2794)
			(end -0.12065 0.2794)
			(stroke
				(width 0.1)
				(type default)
			)
			(layer "F.Fab")
		)
		(fp_line
			(start 0.120396 0.3048)
			(end 0.120396 0.2794)
			(stroke
				(width 0.1)
				(type default)
			)
			(layer "F.Fab")
		)
		(fp_line
			(start 0.12065 -0.3048)
			(end 0.67945 -0.3048)
			(stroke
				(width 0.1)
				(type default)
			)
			(layer "F.Fab")
		)
		(fp_line
			(start 0.12065 -0.2794)
			(end 0.12065 -0.3048)
			(stroke
				(width 0.1)
				(type default)
			)
			(layer "F.Fab")
		)
		(fp_line
			(start 0.67945 -0.3048)
			(end 0.67945 0.3048)
			(stroke
				(width 0.1)
				(type default)
			)
			(layer "F.Fab")
		)
		(fp_line
			(start 0.67945 0.3048)
			(end 0.120396 0.3048)
			(stroke
				(width 0.1)
				(type default)
			)
			(layer "F.Fab")
		)
		(pad "1" smd circle
			(at -0.40005 0)
			(size 0 0)
			(layers "F.Cu" "F.Mask" "F.Paste")
			(net "RST_SMB_SSD_R_N")
		)
		(pad "2" smd circle
			(at 0.40005 0)
			(size 0 0)
			(layers "F.Cu" "F.Mask" "F.Paste")
			(net "RST_SMB_SSD0_N")
		)
	)
)
